(kicad_pcb
	(version 20260206)
	(generator "pcbnew")
	(generator_version "10.0")
	(general
		(thickness 1.6)
		(legacy_teardrops no)
	)
	(paper "A4")
	(title_block
		(title "dpb — 14545-sa.0730WZS0815.brd")
		(comment 1 "Honey Badger (Wiwynn) / footprints 1052-1058 of 1066")
	)
	(layers
		(0 "F.Cu" signal "TOP")
		(4 "In1.Cu" signal "L2GND")
		(6 "In2.Cu" signal "L3")
		(8 "In3.Cu" signal "L4VCC")
		(10 "In4.Cu" signal "L5VCC")
		(12 "In5.Cu" signal "L6")
		(14 "In6.Cu" signal "L7GND")
		(2 "B.Cu" signal "BOTTOM")
		(9 "F.Adhes" user "F.Adhesive")
		(11 "B.Adhes" user "B.Adhesive")
		(13 "F.Paste" user "Package Geometry/Pastemask Top")
		(15 "B.Paste" user "Package Geometry/Pastemask Bottom")
		(5 "F.SilkS" user "Ref Des/Silkscreen Top")
		(7 "B.SilkS" user "Ref Des/Silkscreen Bottom")
		(1 "F.Mask" user "Board Geometry/Soldermask Top")
		(3 "B.Mask" user "Board Geometry/Soldermask Bottom")
		(17 "Dwgs.User" user "User.Drawings")
		(19 "Cmts.User" user "User.Comments")
		(21 "Eco1.User" user "User.Eco1")
		(23 "Eco2.User" user "User.Eco2")
		(25 "Edge.Cuts" user "Board Geometry/Outline")
		(27 "Margin" user)
		(31 "F.CrtYd" user "Package Geometry/Place Bound Top")
		(29 "B.CrtYd" user "Package Geometry/Place Bound Bottom")
		(35 "F.Fab" user "Ref Des/Assembly Top")
		(33 "B.Fab" user "Ref Des/Assembly Bottom")
	)
	(footprint ""
		(layer "F.Cu")
		(at 230.335582 -245.463568 90)
		(property "Reference" "R132"
			(at 0 0 90)
			(layer "F.SilkS")
			(hide yes)
			(effects
				(font
					(size 1.27 1.27)
				)
			)
		)
		(property "Value" "0R2J-2-GP"
			(at 0.064008 -3.993896 90)
			(unlocked yes)
			(layer "F.Fab")
			(hide yes)
			(effects
				(font
					(size 1.016 1.016)
					(thickness 0.1524)
				)
			)
		)
		(property "Device Type" "R402H16"
			(at 0.064008 -5.517896 90)
			(unlocked yes)
			(layer "F.Fab")
			(hide yes)
			(effects
				(font
					(size 1.016 1.016)
					(thickness 0.1524)
				)
			)
		)
		(duplicate_pad_numbers_are_jumpers no)
		(fp_line
			(start 0.508 -0.9398)
			(end -0.508 -0.9398)
			(stroke
				(width 0.1524)
				(type default)
			)
			(layer "F.SilkS")
		)
		(fp_line
			(start -0.508 -0.9398)
			(end -0.508 0.9398)
			(stroke
				(width 0.1524)
				(type default)
			)
			(layer "F.SilkS")
		)
		(fp_rect
			(start -0.508 0.9398)
			(end 0.508 -0.9398)
			(stroke
				(width 0)
				(type default)
			)
			(fill no)
			(layer "F.CrtYd")
		)
		(fp_rect
			(start -0.508 0.9398)
			(end 0.508 -0.9398)
			(stroke
				(width 0)
				(type default)
			)
			(fill no)
			(layer "F.Fab")
		)
		(pad "1" smd custom
			(at 0 -0.4445 90)
			(size 0.1397 0.1397)
			(layers "F.Cu" "F.Mask" "F.Paste")
			(net "FLT_NET_HDD2")
			(options
				(clearance outline)
				(anchor circle)
			)
			(primitives
				(gr_poly
					(pts
						(arc
							(start -0.1778 -0.2794)
							(mid -0.249642 -0.249642)
							(end -0.2794 -0.1778)
						)
						(arc
							(start -0.2794 0.1778)
							(mid -0.249642 0.249642)
							(end -0.1778 0.2794)
						)
						(arc
							(start 0.1778 0.2794)
							(mid 0.249642 0.249642)
							(end 0.2794 0.1778)
						)
						(arc
							(start 0.2794 -0.1778)
							(mid 0.249642 -0.249642)
							(end 0.1778 -0.2794)
						)
					)
					(width 0)
					(fill yes)
				)
			)
		)
		(pad "2" smd custom
			(at 0 0.4445 90)
			(size 0.1397 0.1397)
			(layers "F.Cu" "F.Mask" "F.Paste")
			(net "FLT_HDD2_DRIVE")
			(options
				(clearance outline)
				(anchor circle)
			)
			(primitives
				(gr_poly
					(pts
						(arc
							(start -0.1778 -0.2794)
							(mid -0.249642 -0.249642)
							(end -0.2794 -0.1778)
						)
						(arc
							(start -0.2794 0.1778)
							(mid -0.249642 0.249642)
							(end -0.1778 0.2794)
						)
						(arc
							(start 0.1778 0.2794)
							(mid 0.249642 0.249642)
							(end 0.2794 0.1778)
						)
						(arc
							(start 0.2794 -0.1778)
							(mid 0.249642 -0.249642)
							(end 0.1778 -0.2794)
						)
					)
					(width 0)
					(fill yes)
				)
			)
		)
	)
	(footprint ""
		(layer "F.Cu")
		(at 202.945746 -85.3567 -90)
		(property "Reference" "R438"
			(at 0 0 270)
			(layer "F.SilkS")
			(hide yes)
			(effects
				(font
					(size 1.27 1.27)
				)
			)
		)
		(property "Value" "4K7R2J-2-GP"
			(at 0.064008 -3.993896 270)
			(unlocked yes)
			(layer "F.Fab")
			(hide yes)
			(effects
				(font
					(size 1.016 1.016)
					(thickness 0.1524)
				)
			)
		)
		(property "Device Type" "R402H16"
			(at 0.064008 -5.517896 270)
			(unlocked yes)
			(layer "F.Fab")
			(hide yes)
			(effects
				(font
					(size 1.016 1.016)
					(thickness 0.1524)
				)
			)
		)
		(duplicate_pad_numbers_are_jumpers no)
		(fp_line
			(start -0.508 -0.9398)
			(end -0.508 0.9398)
			(stroke
				(width 0.1524)
				(type default)
			)
			(layer "F.SilkS")
		)
		(fp_line
			(start 0.508 -0.9398)
			(end -0.508 -0.9398)
			(stroke
				(width 0.1524)
				(type default)
			)
			(layer "F.SilkS")
		)
		(fp_rect
			(start -0.508 0.9398)
			(end 0.508 -0.9398)
			(stroke
				(width 0)
				(type default)
			)
			(fill no)
			(layer "F.CrtYd")
		)
		(fp_rect
			(start -0.508 0.9398)
			(end 0.508 -0.9398)
			(stroke
				(width 0)
				(type default)
			)
			(fill no)
			(layer "F.Fab")
		)
		(pad "1" smd custom
			(at 0 -0.4445 270)
			(size 0.1397 0.1397)
			(layers "F.Cu" "F.Mask" "F.Paste")
			(net "P3V3")
			(options
				(clearance outline)
				(anchor circle)
			)
			(primitives
				(gr_poly
					(pts
						(arc
							(start -0.1778 -0.2794)
							(mid -0.249642 -0.249642)
							(end -0.2794 -0.1778)
						)
						(arc
							(start -0.2794 0.1778)
							(mid -0.249642 0.249642)
							(end -0.1778 0.2794)
						)
						(arc
							(start 0.1778 0.2794)
							(mid 0.249642 0.249642)
							(end 0.2794 0.1778)
						)
						(arc
							(start 0.2794 -0.1778)
							(mid 0.249642 -0.249642)
							(end 0.1778 -0.2794)
						)
					)
					(width 0)
					(fill yes)
				)
			)
		)
		(pad "2" smd custom
			(at 0 0.4445 270)
			(size 0.1397 0.1397)
			(layers "F.Cu" "F.Mask" "F.Paste")
			(net "SAS2X28_A_HDD4_FLT")
			(options
				(clearance outline)
				(anchor circle)
			)
			(primitives
				(gr_poly
					(pts
						(arc
							(start -0.1778 -0.2794)
							(mid -0.249642 -0.249642)
							(end -0.2794 -0.1778)
						)
						(arc
							(start -0.2794 0.1778)
							(mid -0.249642 0.249642)
							(end -0.1778 0.2794)
						)
						(arc
							(start 0.1778 0.2794)
							(mid 0.249642 0.249642)
							(end 0.2794 0.1778)
						)
						(arc
							(start 0.2794 -0.1778)
							(mid 0.249642 -0.249642)
							(end 0.1778 -0.2794)
						)
					)
					(width 0)
					(fill yes)
				)
			)
		)
	)
	(footprint ""
		(layer "F.Cu")
		(at 5.84962 -489.442252)
		(property "Reference" "PR48"
			(at 0 0 0)
			(layer "F.SilkS")
			(hide yes)
			(effects
				(font
					(size 1.27 1.27)
				)
			)
		)
		(property "Value" "0R2J-2-GP"
			(at 0.064008 -3.993896 0)
			(unlocked yes)
			(layer "F.Fab")
			(hide yes)
			(effects
				(font
					(size 1.016 1.016)
					(thickness 0.1524)
				)
			)
		)
		(property "Device Type" "R402H16"
			(at 0.064008 -5.517896 0)
			(unlocked yes)
			(layer "F.Fab")
			(hide yes)
			(effects
				(font
					(size 1.016 1.016)
					(thickness 0.1524)
				)
			)
		)
		(duplicate_pad_numbers_are_jumpers no)
		(fp_line
			(start -0.508 -0.9398)
			(end -0.508 0.9398)
			(stroke
				(width 0.1524)
				(type default)
			)
			(layer "F.SilkS")
		)
		(fp_line
			(start 0.508 -0.9398)
			(end -0.508 -0.9398)
			(stroke
				(width 0.1524)
				(type default)
			)
			(layer "F.SilkS")
		)
		(fp_rect
			(start -0.508 0.9398)
			(end 0.508 -0.9398)
			(stroke
				(width 0)
				(type default)
			)
			(fill no)
			(layer "F.CrtYd")
		)
		(fp_rect
			(start -0.508 0.9398)
			(end 0.508 -0.9398)
			(stroke
				(width 0)
				(type default)
			)
			(fill no)
			(layer "F.Fab")
		)
		(pad "1" smd custom
			(at 0 -0.4445)
			(size 0.1397 0.1397)
			(layers "F.Cu" "F.Mask" "F.Paste")
			(net "P5VC_ROVP")
			(options
				(clearance outline)
				(anchor circle)
			)
			(primitives
				(gr_poly
					(pts
						(arc
							(start -0.1778 -0.2794)
							(mid -0.249642 -0.249642)
							(end -0.2794 -0.1778)
						)
						(arc
							(start -0.2794 0.1778)
							(mid -0.249642 0.249642)
							(end -0.1778 0.2794)
						)
						(arc
							(start 0.1778 0.2794)
							(mid 0.249642 0.249642)
							(end 0.2794 0.1778)
						)
						(arc
							(start 0.2794 -0.1778)
							(mid 0.249642 -0.249642)
							(end 0.1778 -0.2794)
						)
					)
					(width 0)
					(fill yes)
				)
			)
		)
		(pad "2" smd custom
			(at 0 0.4445)
			(size 0.1397 0.1397)
			(layers "F.Cu" "F.Mask" "F.Paste")
			(net "P5VC_AGND")
			(options
				(clearance outline)
				(anchor circle)
			)
			(primitives
				(gr_poly
					(pts
						(arc
							(start -0.1778 -0.2794)
							(mid -0.249642 -0.249642)
							(end -0.2794 -0.1778)
						)
						(arc
							(start -0.2794 0.1778)
							(mid -0.249642 0.249642)
							(end -0.1778 0.2794)
						)
						(arc
							(start 0.1778 0.2794)
							(mid 0.249642 0.249642)
							(end 0.2794 0.1778)
						)
						(arc
							(start 0.2794 -0.1778)
							(mid 0.249642 -0.249642)
							(end 0.1778 -0.2794)
						)
					)
					(width 0)
					(fill yes)
				)
			)
		)
	)
	(footprint ""
		(layer "F.Cu")
		(at 46.017688 -23.005288 -90)
		(property "Reference" "PR31"
			(at 0 0 270)
			(layer "F.SilkS")
			(hide yes)
			(effects
				(font
					(size 1.27 1.27)
				)
			)
		)
		(property "Value" "76K8R2F-GP"
			(at 0.064008 -3.993896 270)
			(unlocked yes)
			(layer "F.Fab")
			(hide yes)
			(effects
				(font
					(size 1.016 1.016)
					(thickness 0.1524)
				)
			)
		)
		(property "Device Type" "R402H16"
			(at 0.064008 -5.517896 270)
			(unlocked yes)
			(layer "F.Fab")
			(hide yes)
			(effects
				(font
					(size 1.016 1.016)
					(thickness 0.1524)
				)
			)
		)
		(duplicate_pad_numbers_are_jumpers no)
		(fp_line
			(start -0.508 -0.9398)
			(end -0.508 0.9398)
			(stroke
				(width 0.1524)
				(type default)
			)
			(layer "F.SilkS")
		)
		(fp_line
			(start 0.508 -0.9398)
			(end -0.508 -0.9398)
			(stroke
				(width 0.1524)
				(type default)
			)
			(layer "F.SilkS")
		)
		(fp_rect
			(start -0.508 0.9398)
			(end 0.508 -0.9398)
			(stroke
				(width 0)
				(type default)
			)
			(fill no)
			(layer "F.CrtYd")
		)
		(fp_rect
			(start -0.508 0.9398)
			(end 0.508 -0.9398)
			(stroke
				(width 0)
				(type default)
			)
			(fill no)
			(layer "F.Fab")
		)
		(pad "1" smd custom
			(at 0 -0.4445 270)
			(size 0.1397 0.1397)
			(layers "F.Cu" "F.Mask" "F.Paste")
			(net "P5VB_ROVP")
			(options
				(clearance outline)
				(anchor circle)
			)
			(primitives
				(gr_poly
					(pts
						(arc
							(start -0.1778 -0.2794)
							(mid -0.249642 -0.249642)
							(end -0.2794 -0.1778)
						)
						(arc
							(start -0.2794 0.1778)
							(mid -0.249642 0.249642)
							(end -0.1778 0.2794)
						)
						(arc
							(start 0.1778 0.2794)
							(mid 0.249642 0.249642)
							(end 0.2794 0.1778)
						)
						(arc
							(start 0.2794 -0.1778)
							(mid 0.249642 -0.249642)
							(end 0.1778 -0.2794)
						)
					)
					(width 0)
					(fill yes)
				)
			)
		)
		(pad "2" smd custom
			(at 0 0.4445 270)
			(size 0.1397 0.1397)
			(layers "F.Cu" "F.Mask" "F.Paste")
			(net "P5VB")
			(options
				(clearance outline)
				(anchor circle)
			)
			(primitives
				(gr_poly
					(pts
						(arc
							(start -0.1778 -0.2794)
							(mid -0.249642 -0.249642)
							(end -0.2794 -0.1778)
						)
						(arc
							(start -0.2794 0.1778)
							(mid -0.249642 0.249642)
							(end -0.1778 0.2794)
						)
						(arc
							(start 0.1778 0.2794)
							(mid 0.249642 0.249642)
							(end 0.2794 0.1778)
						)
						(arc
							(start 0.2794 -0.1778)
							(mid 0.249642 -0.249642)
							(end 0.1778 -0.2794)
						)
					)
					(width 0)
					(fill yes)
				)
			)
		)
	)
	(footprint ""
		(layer "F.Cu")
		(at 196.088 -393.065 180)
		(property "Reference" "R409"
			(at 0 0 180)
			(layer "F.SilkS")
			(hide yes)
			(effects
				(font
					(size 1.27 1.27)
				)
			)
		)
		(property "Value" "0R2J-2-GP"
			(at 0.064008 -3.993896 180)
			(unlocked yes)
			(layer "F.Fab")
			(hide yes)
			(effects
				(font
					(size 1.016 1.016)
					(thickness 0.1524)
				)
			)
		)
		(property "Device Type" "R402H16"
			(at 0.064008 -5.517896 180)
			(unlocked yes)
			(layer "F.Fab")
			(hide yes)
			(effects
				(font
					(size 1.016 1.016)
					(thickness 0.1524)
				)
			)
		)
		(duplicate_pad_numbers_are_jumpers no)
		(fp_line
			(start 0.508 -0.9398)
			(end -0.508 -0.9398)
			(stroke
				(width 0.1524)
				(type default)
			)
			(layer "F.SilkS")
		)
		(fp_line
			(start -0.508 -0.9398)
			(end -0.508 0.9398)
			(stroke
				(width 0.1524)
				(type default)
			)
			(layer "F.SilkS")
		)
		(fp_rect
			(start -0.508 0.9398)
			(end 0.508 -0.9398)
			(stroke
				(width 0)
				(type default)
			)
			(fill no)
			(layer "F.CrtYd")
		)
		(fp_rect
			(start -0.508 0.9398)
			(end 0.508 -0.9398)
			(stroke
				(width 0)
				(type default)
			)
			(fill no)
			(layer "F.Fab")
		)
		(pad "1" smd custom
			(at 0 -0.4445 180)
			(size 0.1397 0.1397)
			(layers "F.Cu" "F.Mask" "F.Paste")
			(net "SW_HDD1_G")
			(options
				(clearance outline)
				(anchor circle)
			)
			(primitives
				(gr_poly
					(pts
						(arc
							(start -0.1778 -0.2794)
							(mid -0.249642 -0.249642)
							(end -0.2794 -0.1778)
						)
						(arc
							(start -0.2794 0.1778)
							(mid -0.249642 0.249642)
							(end -0.1778 0.2794)
						)
						(arc
							(start 0.1778 0.2794)
							(mid 0.249642 0.249642)
							(end 0.2794 0.1778)
						)
						(arc
							(start 0.2794 -0.1778)
							(mid 0.249642 -0.249642)
							(end 0.1778 -0.2794)
						)
					)
					(width 0)
					(fill yes)
				)
			)
		)
		(pad "2" smd custom
			(at 0 0.4445 180)
			(size 0.1397 0.1397)
			(layers "F.Cu" "F.Mask" "F.Paste")
			(net "SW_HDD1_R")
			(options
				(clearance outline)
				(anchor circle)
			)
			(primitives
				(gr_poly
					(pts
						(arc
							(start -0.1778 -0.2794)
							(mid -0.249642 -0.249642)
							(end -0.2794 -0.1778)
						)
						(arc
							(start -0.2794 0.1778)
							(mid -0.249642 0.249642)
							(end -0.1778 0.2794)
						)
						(arc
							(start 0.1778 0.2794)
							(mid 0.249642 0.249642)
							(end 0.2794 0.1778)
						)
						(arc
							(start 0.2794 -0.1778)
							(mid 0.249642 -0.249642)
							(end 0.1778 -0.2794)
						)
					)
					(width 0)
					(fill yes)
				)
			)
		)
	)
	(footprint ""
		(layer "F.Cu")
		(at 20.574 -257.302 90)
		(property "Reference" "R271"
			(at 0 0 90)
			(layer "F.SilkS")
			(hide yes)
			(effects
				(font
					(size 1.27 1.27)
				)
			)
		)
		(property "Value" "330R2F-GP"
			(at 0.064008 -3.993896 90)
			(unlocked yes)
			(layer "F.Fab")
			(hide yes)
			(effects
				(font
					(size 1.016 1.016)
					(thickness 0.1524)
				)
			)
		)
		(property "Device Type" "R402H16"
			(at 0.064008 -5.517896 90)
			(unlocked yes)
			(layer "F.Fab")
			(hide yes)
			(effects
				(font
					(size 1.016 1.016)
					(thickness 0.1524)
				)
			)
		)
		(duplicate_pad_numbers_are_jumpers no)
		(fp_line
			(start 0.508 -0.9398)
			(end -0.508 -0.9398)
			(stroke
				(width 0.1524)
				(type default)
			)
			(layer "F.SilkS")
		)
		(fp_line
			(start -0.508 -0.9398)
			(end -0.508 0.9398)
			(stroke
				(width 0.1524)
				(type default)
			)
			(layer "F.SilkS")
		)
		(fp_rect
			(start -0.508 0.9398)
			(end 0.508 -0.9398)
			(stroke
				(width 0)
				(type default)
			)
			(fill no)
			(layer "F.CrtYd")
		)
		(fp_rect
			(start -0.508 0.9398)
			(end 0.508 -0.9398)
			(stroke
				(width 0)
				(type default)
			)
			(fill no)
			(layer "F.Fab")
		)
		(pad "1" smd custom
			(at 0 -0.4445 90)
			(size 0.1397 0.1397)
			(layers "F.Cu" "F.Mask" "F.Paste")
			(net "P3V3_HDD12_LED")
			(options
				(clearance outline)
				(anchor circle)
			)
			(primitives
				(gr_poly
					(pts
						(arc
							(start -0.1778 -0.2794)
							(mid -0.249642 -0.249642)
							(end -0.2794 -0.1778)
						)
						(arc
							(start -0.2794 0.1778)
							(mid -0.249642 0.249642)
							(end -0.1778 0.2794)
						)
						(arc
							(start 0.1778 0.2794)
							(mid 0.249642 0.249642)
							(end 0.2794 0.1778)
						)
						(arc
							(start 0.2794 -0.1778)
							(mid 0.249642 -0.249642)
							(end 0.1778 -0.2794)
						)
					)
					(width 0)
					(fill yes)
				)
			)
		)
		(pad "2" smd custom
			(at 0 0.4445 90)
			(size 0.1397 0.1397)
			(layers "F.Cu" "F.Mask" "F.Paste")
			(net "FLT_HDD12")
			(options
				(clearance outline)
				(anchor circle)
			)
			(primitives
				(gr_poly
					(pts
						(arc
							(start -0.1778 -0.2794)
							(mid -0.249642 -0.249642)
							(end -0.2794 -0.1778)
						)
						(arc
							(start -0.2794 0.1778)
							(mid -0.249642 0.249642)
							(end -0.1778 0.2794)
						)
						(arc
							(start 0.1778 0.2794)
							(mid 0.249642 0.249642)
							(end 0.2794 0.1778)
						)
						(arc
							(start 0.2794 -0.1778)
							(mid 0.249642 -0.249642)
							(end 0.1778 -0.2794)
						)
					)
					(width 0)
					(fill yes)
				)
			)
		)
	)
	(footprint ""
		(layer "F.Cu")
		(at 35.6616 -339.2932 -90)
		(property "Reference" "R399"
			(at 0 0 270)
			(layer "F.SilkS")
			(hide yes)
			(effects
				(font
					(size 1.27 1.27)
				)
			)
		)
		(property "Value" "10KR2F-2-GP"
			(at 0.064008 -3.993896 270)
			(unlocked yes)
			(layer "F.Fab")
			(hide yes)
			(effects
				(font
					(size 1.016 1.016)
					(thickness 0.1524)
				)
			)
		)
		(property "Device Type" "R402H16"
			(at 0.064008 -5.517896 270)
			(unlocked yes)
			(layer "F.Fab")
			(hide yes)
			(effects
				(font
					(size 1.016 1.016)
					(thickness 0.1524)
				)
			)
		)
		(duplicate_pad_numbers_are_jumpers no)
		(fp_line
			(start -0.508 -0.9398)
			(end -0.508 0.9398)
			(stroke
				(width 0.1524)
				(type default)
			)
			(layer "F.SilkS")
		)
		(fp_line
			(start 0.508 -0.9398)
			(end -0.508 -0.9398)
			(stroke
				(width 0.1524)
				(type default)
			)
			(layer "F.SilkS")
		)
		(fp_rect
			(start -0.508 0.9398)
			(end 0.508 -0.9398)
			(stroke
				(width 0)
				(type default)
			)
			(fill no)
			(layer "F.CrtYd")
		)
		(fp_rect
			(start -0.508 0.9398)
			(end 0.508 -0.9398)
			(stroke
				(width 0)
				(type default)
			)
			(fill no)
			(layer "F.Fab")
		)
		(pad "1" smd custom
			(at 0 -0.4445 270)
			(size 0.1397 0.1397)
			(layers "F.Cu" "F.Mask" "F.Paste")
			(net "P12V")
			(options
				(clearance outline)
				(anchor circle)
			)
			(primitives
				(gr_poly
					(pts
						(arc
							(start -0.1778 -0.2794)
							(mid -0.249642 -0.249642)
							(end -0.2794 -0.1778)
						)
						(arc
							(start -0.2794 0.1778)
							(mid -0.249642 0.249642)
							(end -0.1778 0.2794)
						)
						(arc
							(start 0.1778 0.2794)
							(mid 0.249642 0.249642)
							(end 0.2794 0.1778)
						)
						(arc
							(start 0.2794 -0.1778)
							(mid 0.249642 -0.249642)
							(end 0.1778 -0.2794)
						)
					)
					(width 0)
					(fill yes)
				)
			)
		)
		(pad "2" smd custom
			(at 0 0.4445 270)
			(size 0.1397 0.1397)
			(layers "F.Cu" "F.Mask" "F.Paste")
			(net "HDD11_LED_G")
			(options
				(clearance outline)
				(anchor circle)
			)
			(primitives
				(gr_poly
					(pts
						(arc
							(start -0.1778 -0.2794)
							(mid -0.249642 -0.249642)
							(end -0.2794 -0.1778)
						)
						(arc
							(start -0.2794 0.1778)
							(mid -0.249642 0.249642)
							(end -0.1778 0.2794)
						)
						(arc
							(start 0.1778 0.2794)
							(mid 0.249642 0.249642)
							(end 0.2794 0.1778)
						)
						(arc
							(start 0.2794 -0.1778)
							(mid 0.249642 -0.249642)
							(end 0.1778 -0.2794)
						)
					)
					(width 0)
					(fill yes)
				)
			)
		)
	)
)
